(kicad_pcb
	(version 20260206)
	(generator "pcbnew")
	(generator_version "10.0")
	(general
		(thickness 1.6)
		(legacy_teardrops no)
	)
	(paper "A4")
	(title_block
		(title "01162023_DA0F0TEBIF0_F0T_Expander_BD_F_brd_V02_OCP.brd")
		(comment 1 "Grand Teton / footprints 2221-2227 of 9728")
	)
	(layers
		(0 "F.Cu" signal "TOP")
		(4 "In1.Cu" signal "GND")
		(6 "In2.Cu" signal "VCC")
		(8 "In3.Cu" signal "VCC1")
		(10 "In4.Cu" signal "GND1")
		(12 "In5.Cu" signal "IN1")
		(14 "In6.Cu" signal "GND2")
		(16 "In7.Cu" signal "IN2")
		(18 "In8.Cu" signal "GND3")
		(20 "In9.Cu" signal "IN3")
		(22 "In10.Cu" signal "GND4")
		(24 "In11.Cu" signal "IN4")
		(26 "In12.Cu" signal "GND5")
		(28 "In13.Cu" signal "IN5")
		(30 "In14.Cu" signal "GND6")
		(32 "In15.Cu" signal "IN6")
		(34 "In16.Cu" signal "GND7")
		(2 "B.Cu" signal "BOTTOM")
		(9 "F.Adhes" user "F.Adhesive")
		(11 "B.Adhes" user "B.Adhesive")
		(13 "F.Paste" user "Package Geometry/Pastemask Top")
		(15 "B.Paste" user "Package Geometry/Pastemask Bottom")
		(5 "F.SilkS" user "Ref Des/Silkscreen Top")
		(7 "B.SilkS" user "Ref Des/Silkscreen Bottom")
		(1 "F.Mask" user "Board Geometry/Soldermask Top")
		(3 "B.Mask" user "Board Geometry/Soldermask Bottom")
		(17 "Dwgs.User" user "User.Drawings")
		(19 "Cmts.User" user "User.Comments")
		(21 "Eco1.User" user "User.Eco1")
		(23 "Eco2.User" user "User.Eco2")
		(25 "Edge.Cuts" user "Board Geometry/Outline")
		(27 "Margin" user)
		(31 "F.CrtYd" user "Package Geometry/Place Bound Top")
		(29 "B.CrtYd" user "Package Geometry/Place Bound Bottom")
		(35 "F.Fab" user "Ref Des/Assembly Top")
		(33 "B.Fab" user "Ref Des/Assembly Bottom")
	)
	(footprint ""
		(layer "F.Cu")
		(at 52.025042 -14.735302 180)
		(property "Reference" "C2714"
			(at 0 0 180)
			(layer "F.SilkS")
			(hide yes)
			(effects
				(font
					(size 1.27 1.27)
				)
			)
		)
		(property "Value" ""
			(at 0 0 180)
			(layer "F.Fab")
			(effects
				(font
					(size 1.27 1.27)
				)
			)
		)
		(duplicate_pad_numbers_are_jumpers no)
		(fp_line
			(start 0.7874 0.4064)
			(end -0.7874 0.4064)
			(stroke
				(width 0.1524)
				(type default)
			)
			(layer "F.SilkS")
		)
		(fp_line
			(start 0.7874 -0.4064)
			(end 0.7874 0.4064)
			(stroke
				(width 0.1524)
				(type default)
			)
			(layer "F.SilkS")
		)
		(fp_line
			(start -0.7874 0.4064)
			(end -0.7874 -0.4064)
			(stroke
				(width 0.1524)
				(type default)
			)
			(layer "F.SilkS")
		)
		(fp_line
			(start -0.7874 -0.4064)
			(end 0.7874 -0.4064)
			(stroke
				(width 0.1524)
				(type default)
			)
			(layer "F.SilkS")
		)
		(fp_line
			(start 0.67945 0.3048)
			(end 0.120396 0.3048)
			(stroke
				(width 0.1)
				(type default)
			)
			(layer "F.Fab")
		)
		(fp_line
			(start 0.67945 -0.3048)
			(end 0.67945 0.3048)
			(stroke
				(width 0.1)
				(type default)
			)
			(layer "F.Fab")
		)
		(fp_line
			(start 0.12065 -0.2794)
			(end 0.12065 -0.3048)
			(stroke
				(width 0.1)
				(type default)
			)
			(layer "F.Fab")
		)
		(fp_line
			(start 0.12065 -0.3048)
			(end 0.67945 -0.3048)
			(stroke
				(width 0.1)
				(type default)
			)
			(layer "F.Fab")
		)
		(fp_line
			(start 0.120396 0.3048)
			(end 0.120396 0.2794)
			(stroke
				(width 0.1)
				(type default)
			)
			(layer "F.Fab")
		)
		(fp_line
			(start 0.120396 0.2794)
			(end -0.12065 0.2794)
			(stroke
				(width 0.1)
				(type default)
			)
			(layer "F.Fab")
		)
		(fp_line
			(start -0.12065 0.3048)
			(end -0.67945 0.3048)
			(stroke
				(width 0.1)
				(type default)
			)
			(layer "F.Fab")
		)
		(fp_line
			(start -0.12065 0.2794)
			(end -0.12065 0.3048)
			(stroke
				(width 0.1)
				(type default)
			)
			(layer "F.Fab")
		)
		(fp_line
			(start -0.12065 -0.2794)
			(end 0.12065 -0.2794)
			(stroke
				(width 0.1)
				(type default)
			)
			(layer "F.Fab")
		)
		(fp_line
			(start -0.12065 -0.305054)
			(end -0.12065 -0.2794)
			(stroke
				(width 0.1)
				(type default)
			)
			(layer "F.Fab")
		)
		(fp_line
			(start -0.67945 0.3048)
			(end -0.67945 -0.305054)
			(stroke
				(width 0.1)
				(type default)
			)
			(layer "F.Fab")
		)
		(fp_line
			(start -0.67945 -0.305054)
			(end -0.12065 -0.305054)
			(stroke
				(width 0.1)
				(type default)
			)
			(layer "F.Fab")
		)
		(pad "1" smd circle
			(at -0.40005 0 180)
			(size 0 0)
			(layers "F.Cu" "F.Mask" "F.Paste")
			(net "GND")
		)
		(pad "2" smd circle
			(at 0.40005 0 180)
			(size 0 0)
			(layers "F.Cu" "F.Mask" "F.Paste")
			(net "P3V3_SSD1")
		)
	)
	(footprint ""
		(layer "F.Cu")
		(at 99.57943 -385.177792 180)
		(property "Reference" "R6293"
			(at 0 0 180)
			(layer "F.SilkS")
			(hide yes)
			(effects
				(font
					(size 1.27 1.27)
				)
			)
		)
		(property "Value" ""
			(at 0 0 180)
			(layer "F.Fab")
			(effects
				(font
					(size 1.27 1.27)
				)
			)
		)
		(duplicate_pad_numbers_are_jumpers no)
		(fp_line
			(start 0.7874 0.4064)
			(end -0.7874 0.4064)
			(stroke
				(width 0.1524)
				(type default)
			)
			(layer "F.SilkS")
		)
		(fp_line
			(start 0.7874 -0.4064)
			(end 0.7874 0.4064)
			(stroke
				(width 0.1524)
				(type default)
			)
			(layer "F.SilkS")
		)
		(fp_line
			(start -0.7874 -0.4064)
			(end 0.7874 -0.4064)
			(stroke
				(width 0.1524)
				(type default)
			)
			(layer "F.SilkS")
		)
		(fp_line
			(start 0.67945 0.3048)
			(end 0.120396 0.3048)
			(stroke
				(width 0.1)
				(type default)
			)
			(layer "F.Fab")
		)
		(fp_line
			(start 0.67945 -0.3048)
			(end 0.67945 0.3048)
			(stroke
				(width 0.1)
				(type default)
			)
			(layer "F.Fab")
		)
		(fp_line
			(start 0.12065 -0.2794)
			(end 0.12065 -0.3048)
			(stroke
				(width 0.1)
				(type default)
			)
			(layer "F.Fab")
		)
		(fp_line
			(start 0.12065 -0.3048)
			(end 0.67945 -0.3048)
			(stroke
				(width 0.1)
				(type default)
			)
			(layer "F.Fab")
		)
		(fp_line
			(start 0.120396 0.3048)
			(end 0.120396 0.2794)
			(stroke
				(width 0.1)
				(type default)
			)
			(layer "F.Fab")
		)
		(fp_line
			(start 0.120396 0.2794)
			(end -0.12065 0.2794)
			(stroke
				(width 0.1)
				(type default)
			)
			(layer "F.Fab")
		)
		(fp_line
			(start -0.12065 0.3048)
			(end -0.67945 0.3048)
			(stroke
				(width 0.1)
				(type default)
			)
			(layer "F.Fab")
		)
		(fp_line
			(start -0.12065 0.2794)
			(end -0.12065 0.3048)
			(stroke
				(width 0.1)
				(type default)
			)
			(layer "F.Fab")
		)
		(fp_line
			(start -0.12065 -0.2794)
			(end 0.12065 -0.2794)
			(stroke
				(width 0.1)
				(type default)
			)
			(layer "F.Fab")
		)
		(fp_line
			(start -0.12065 -0.305054)
			(end -0.12065 -0.2794)
			(stroke
				(width 0.1)
				(type default)
			)
			(layer "F.Fab")
		)
		(fp_line
			(start -0.67945 0.3048)
			(end -0.67945 -0.305054)
			(stroke
				(width 0.1)
				(type default)
			)
			(layer "F.Fab")
		)
		(fp_line
			(start -0.67945 -0.305054)
			(end -0.12065 -0.305054)
			(stroke
				(width 0.1)
				(type default)
			)
			(layer "F.Fab")
		)
		(pad "1" smd rect
			(at -0.40005 0)
			(size 0.4572 0.508)
			(layers "F.Cu" "F.Mask" "F.Paste")
			(net "USB2_MB_BMC_DN")
		)
		(pad "2" smd rect
			(at 0.40005 0)
			(size 0.4572 0.508)
			(layers "F.Cu" "F.Mask" "F.Paste")
			(net "GND")
		)
	)
	(footprint ""
		(layer "F.Cu")
		(at 267.394944 -59.577986 90)
		(property "Reference" "PC566"
			(at 0 0 90)
			(layer "F.SilkS")
			(hide yes)
			(effects
				(font
					(size 1.27 1.27)
				)
			)
		)
		(property "Value" ""
			(at 0 0 90)
			(layer "F.Fab")
			(effects
				(font
					(size 1.27 1.27)
				)
			)
		)
		(duplicate_pad_numbers_are_jumpers no)
		(fp_line
			(start 0.7874 -0.4064)
			(end 0.7874 0.4064)
			(stroke
				(width 0.1524)
				(type default)
			)
			(layer "F.SilkS")
		)
		(fp_line
			(start -0.7874 -0.4064)
			(end 0.7874 -0.4064)
			(stroke
				(width 0.1524)
				(type default)
			)
			(layer "F.SilkS")
		)
		(fp_line
			(start 0.7874 0.4064)
			(end -0.7874 0.4064)
			(stroke
				(width 0.1524)
				(type default)
			)
			(layer "F.SilkS")
		)
		(fp_line
			(start -0.7874 0.4064)
			(end -0.7874 -0.4064)
			(stroke
				(width 0.1524)
				(type default)
			)
			(layer "F.SilkS")
		)
		(fp_line
			(start -0.12065 -0.305054)
			(end -0.12065 -0.2794)
			(stroke
				(width 0.1)
				(type default)
			)
			(layer "F.Fab")
		)
		(fp_line
			(start -0.67945 -0.305054)
			(end -0.12065 -0.305054)
			(stroke
				(width 0.1)
				(type default)
			)
			(layer "F.Fab")
		)
		(fp_line
			(start 0.67945 -0.3048)
			(end 0.67945 0.3048)
			(stroke
				(width 0.1)
				(type default)
			)
			(layer "F.Fab")
		)
		(fp_line
			(start 0.12065 -0.3048)
			(end 0.67945 -0.3048)
			(stroke
				(width 0.1)
				(type default)
			)
			(layer "F.Fab")
		)
		(fp_line
			(start 0.12065 -0.2794)
			(end 0.12065 -0.3048)
			(stroke
				(width 0.1)
				(type default)
			)
			(layer "F.Fab")
		)
		(fp_line
			(start -0.12065 -0.2794)
			(end 0.12065 -0.2794)
			(stroke
				(width 0.1)
				(type default)
			)
			(layer "F.Fab")
		)
		(fp_line
			(start 0.120396 0.2794)
			(end -0.12065 0.2794)
			(stroke
				(width 0.1)
				(type default)
			)
			(layer "F.Fab")
		)
		(fp_line
			(start -0.12065 0.2794)
			(end -0.12065 0.3048)
			(stroke
				(width 0.1)
				(type default)
			)
			(layer "F.Fab")
		)
		(fp_line
			(start 0.67945 0.3048)
			(end 0.120396 0.3048)
			(stroke
				(width 0.1)
				(type default)
			)
			(layer "F.Fab")
		)
		(fp_line
			(start 0.120396 0.3048)
			(end 0.120396 0.2794)
			(stroke
				(width 0.1)
				(type default)
			)
			(layer "F.Fab")
		)
		(fp_line
			(start -0.12065 0.3048)
			(end -0.67945 0.3048)
			(stroke
				(width 0.1)
				(type default)
			)
			(layer "F.Fab")
		)
		(fp_line
			(start -0.67945 0.3048)
			(end -0.67945 -0.305054)
			(stroke
				(width 0.1)
				(type default)
			)
			(layer "F.Fab")
		)
		(pad "1" smd circle
			(at -0.40005 0 90)
			(size 0 0)
			(layers "F.Cu" "F.Mask" "F.Paste")
			(net "P3V3_SSD9_SS")
		)
		(pad "2" smd circle
			(at 0.40005 0 90)
			(size 0 0)
			(layers "F.Cu" "F.Mask" "F.Paste")
			(net "GND")
		)
	)
	(footprint ""
		(layer "F.Cu")
		(at 358.41051 -121.661428 180)
		(property "Reference" "C2882"
			(at 0 0 180)
			(layer "F.SilkS")
			(hide yes)
			(effects
				(font
					(size 1.27 1.27)
				)
			)
		)
		(property "Value" ""
			(at 0 0 180)
			(layer "F.Fab")
			(effects
				(font
					(size 1.27 1.27)
				)
			)
		)
		(duplicate_pad_numbers_are_jumpers no)
		(fp_line
			(start 0.7874 0.4064)
			(end -0.7874 0.4064)
			(stroke
				(width 0.1524)
				(type default)
			)
			(layer "F.SilkS")
		)
		(fp_line
			(start 0.7874 -0.4064)
			(end 0.7874 0.4064)
			(stroke
				(width 0.1524)
				(type default)
			)
			(layer "F.SilkS")
		)
		(fp_line
			(start -0.7874 0.4064)
			(end -0.7874 -0.4064)
			(stroke
				(width 0.1524)
				(type default)
			)
			(layer "F.SilkS")
		)
		(fp_line
			(start -0.7874 -0.4064)
			(end 0.7874 -0.4064)
			(stroke
				(width 0.1524)
				(type default)
			)
			(layer "F.SilkS")
		)
		(fp_line
			(start 0.67945 0.3048)
			(end 0.120396 0.3048)
			(stroke
				(width 0.1)
				(type default)
			)
			(layer "F.Fab")
		)
		(fp_line
			(start 0.67945 -0.3048)
			(end 0.67945 0.3048)
			(stroke
				(width 0.1)
				(type default)
			)
			(layer "F.Fab")
		)
		(fp_line
			(start 0.12065 -0.2794)
			(end 0.12065 -0.3048)
			(stroke
				(width 0.1)
				(type default)
			)
			(layer "F.Fab")
		)
		(fp_line
			(start 0.12065 -0.3048)
			(end 0.67945 -0.3048)
			(stroke
				(width 0.1)
				(type default)
			)
			(layer "F.Fab")
		)
		(fp_line
			(start 0.120396 0.3048)
			(end 0.120396 0.2794)
			(stroke
				(width 0.1)
				(type default)
			)
			(layer "F.Fab")
		)
		(fp_line
			(start 0.120396 0.2794)
			(end -0.12065 0.2794)
			(stroke
				(width 0.1)
				(type default)
			)
			(layer "F.Fab")
		)
		(fp_line
			(start -0.12065 0.3048)
			(end -0.67945 0.3048)
			(stroke
				(width 0.1)
				(type default)
			)
			(layer "F.Fab")
		)
		(fp_line
			(start -0.12065 0.2794)
			(end -0.12065 0.3048)
			(stroke
				(width 0.1)
				(type default)
			)
			(layer "F.Fab")
		)
		(fp_line
			(start -0.12065 -0.2794)
			(end 0.12065 -0.2794)
			(stroke
				(width 0.1)
				(type default)
			)
			(layer "F.Fab")
		)
		(fp_line
			(start -0.12065 -0.305054)
			(end -0.12065 -0.2794)
			(stroke
				(width 0.1)
				(type default)
			)
			(layer "F.Fab")
		)
		(fp_line
			(start -0.67945 0.3048)
			(end -0.67945 -0.305054)
			(stroke
				(width 0.1)
				(type default)
			)
			(layer "F.Fab")
		)
		(fp_line
			(start -0.67945 -0.305054)
			(end -0.12065 -0.305054)
			(stroke
				(width 0.1)
				(type default)
			)
			(layer "F.Fab")
		)
		(pad "1" smd circle
			(at -0.40005 0 180)
			(size 0 0)
			(layers "F.Cu" "F.Mask" "F.Paste")
			(net "HP_NIC6_EN")
		)
		(pad "2" smd circle
			(at 0.40005 0 180)
			(size 0 0)
			(layers "F.Cu" "F.Mask" "F.Paste")
			(net "GND")
		)
	)
	(footprint ""
		(layer "F.Cu")
		(at 407.67 -383.667 -90)
		(property "Reference" "R6282"
			(at 0 0 270)
			(layer "F.SilkS")
			(hide yes)
			(effects
				(font
					(size 1.27 1.27)
				)
			)
		)
		(property "Value" ""
			(at 0 0 270)
			(layer "F.Fab")
			(effects
				(font
					(size 1.27 1.27)
				)
			)
		)
		(duplicate_pad_numbers_are_jumpers no)
		(fp_line
			(start -0.7874 0.4064)
			(end -0.7874 -0.4064)
			(stroke
				(width 0.1524)
				(type default)
			)
			(layer "F.SilkS")
		)
		(fp_line
			(start 0.7874 0.4064)
			(end -0.7874 0.4064)
			(stroke
				(width 0.1524)
				(type default)
			)
			(layer "F.SilkS")
		)
		(fp_line
			(start -0.7874 -0.4064)
			(end 0.7874 -0.4064)
			(stroke
				(width 0.1524)
				(type default)
			)
			(layer "F.SilkS")
		)
		(fp_line
			(start 0.7874 -0.4064)
			(end 0.7874 0.4064)
			(stroke
				(width 0.1524)
				(type default)
			)
			(layer "F.SilkS")
		)
		(fp_line
			(start -0.67945 0.3048)
			(end -0.67945 -0.305054)
			(stroke
				(width 0.1)
				(type default)
			)
			(layer "F.Fab")
		)
		(fp_line
			(start -0.12065 0.3048)
			(end -0.67945 0.3048)
			(stroke
				(width 0.1)
				(type default)
			)
			(layer "F.Fab")
		)
		(fp_line
			(start 0.120396 0.3048)
			(end 0.120396 0.2794)
			(stroke
				(width 0.1)
				(type default)
			)
			(layer "F.Fab")
		)
		(fp_line
			(start 0.67945 0.3048)
			(end 0.120396 0.3048)
			(stroke
				(width 0.1)
				(type default)
			)
			(layer "F.Fab")
		)
		(fp_line
			(start -0.12065 0.2794)
			(end -0.12065 0.3048)
			(stroke
				(width 0.1)
				(type default)
			)
			(layer "F.Fab")
		)
		(fp_line
			(start 0.120396 0.2794)
			(end -0.12065 0.2794)
			(stroke
				(width 0.1)
				(type default)
			)
			(layer "F.Fab")
		)
		(fp_line
			(start -0.12065 -0.2794)
			(end 0.12065 -0.2794)
			(stroke
				(width 0.1)
				(type default)
			)
			(layer "F.Fab")
		)
		(fp_line
			(start 0.12065 -0.2794)
			(end 0.12065 -0.3048)
			(stroke
				(width 0.1)
				(type default)
			)
			(layer "F.Fab")
		)
		(fp_line
			(start 0.12065 -0.3048)
			(end 0.67945 -0.3048)
			(stroke
				(width 0.1)
				(type default)
			)
			(layer "F.Fab")
		)
		(fp_line
			(start 0.67945 -0.3048)
			(end 0.67945 0.3048)
			(stroke
				(width 0.1)
				(type default)
			)
			(layer "F.Fab")
		)
		(fp_line
			(start -0.67945 -0.305054)
			(end -0.12065 -0.305054)
			(stroke
				(width 0.1)
				(type default)
			)
			(layer "F.Fab")
		)
		(fp_line
			(start -0.12065 -0.305054)
			(end -0.12065 -0.2794)
			(stroke
				(width 0.1)
				(type default)
			)
			(layer "F.Fab")
		)
		(pad "1" smd circle
			(at -0.40005 0 270)
			(size 0 0)
			(layers "F.Cu" "F.Mask" "F.Paste")
			(net "P3V3_AUX")
		)
		(pad "2" smd circle
			(at 0.40005 0 270)
			(size 0 0)
			(layers "F.Cu" "F.Mask" "F.Paste")
			(net "I3C_MB_BMC_R_SDA")
		)
	)
	(footprint ""
		(layer "F.Cu")
		(at 440.359292 -343.952322 90)
		(property "Reference" "C796"
			(at 0 0 90)
			(layer "F.SilkS")
			(hide yes)
			(effects
				(font
					(size 1.27 1.27)
				)
			)
		)
		(property "Value" ""
			(at 0 0 90)
			(layer "F.Fab")
			(effects
				(font
					(size 1.27 1.27)
				)
			)
		)
		(duplicate_pad_numbers_are_jumpers no)
		(fp_line
			(start 0.299974 -0.150114)
			(end 0.299974 0.150114)
			(stroke
				(width 0.1)
				(type default)
			)
			(layer "F.Fab")
		)
		(fp_line
			(start -0.299974 -0.150114)
			(end 0.299974 -0.150114)
			(stroke
				(width 0.1)
				(type default)
			)
			(layer "F.Fab")
		)
		(fp_line
			(start 0.299974 0.150114)
			(end -0.299974 0.150114)
			(stroke
				(width 0.1)
				(type default)
			)
			(layer "F.Fab")
		)
		(fp_line
			(start -0.299974 0.150114)
			(end -0.299974 -0.150114)
			(stroke
				(width 0.1)
				(type default)
			)
			(layer "F.Fab")
		)
		(pad "1" smd rect
			(at -0.2667 0 90)
			(size 0.3048 0.381)
			(layers "F.Cu" "F.Mask" "F.Paste")
			(net "P5E_PEX3_STN7_TX_DP<126>")
		)
		(pad "2" smd rect
			(at 0.2667 0 90)
			(size 0.3048 0.381)
			(layers "F.Cu" "F.Mask" "F.Paste")
			(net "P5E_PEX3_STN7_TX_C_DP<126>")
		)
	)
	(footprint ""
		(layer "F.Cu")
		(at 428.319438 -146.190208 180)
		(property "Reference" "C645"
			(at 0 0 180)
			(layer "F.SilkS")
			(hide yes)
			(effects
				(font
					(size 1.27 1.27)
				)
			)
		)
		(property "Value" ""
			(at 0 0 180)
			(layer "F.Fab")
			(effects
				(font
					(size 1.27 1.27)
				)
			)
		)
		(duplicate_pad_numbers_are_jumpers no)
		(fp_line
			(start 0.299974 0.150114)
			(end -0.299974 0.150114)
			(stroke
				(width 0.1)
				(type default)
			)
			(layer "F.Fab")
		)
		(fp_line
			(start 0.299974 -0.150114)
			(end 0.299974 0.150114)
			(stroke
				(width 0.1)
				(type default)
			)
			(layer "F.Fab")
		)
		(fp_line
			(start -0.299974 0.150114)
			(end -0.299974 -0.150114)
			(stroke
				(width 0.1)
				(type default)
			)
			(layer "F.Fab")
		)
		(fp_line
			(start -0.299974 -0.150114)
			(end 0.299974 -0.150114)
			(stroke
				(width 0.1)
				(type default)
			)
			(layer "F.Fab")
		)
		(pad "1" smd rect
			(at -0.2667 0 180)
			(size 0.3048 0.381)
			(layers "F.Cu" "F.Mask" "F.Paste")
			(net "P5E_PEX3_STN0_TX_DN<10>")
		)
		(pad "2" smd rect
			(at 0.2667 0 180)
			(size 0.3048 0.381)
			(layers "F.Cu" "F.Mask" "F.Paste")
			(net "P5E_PEX3_STN0_TX_C_DN<10>")
		)
	)
)
